(kicad_pcb
	(version 20260206)
	(generator "pcbnew")
	(generator_version "10.0")
	(general
		(thickness 1.6)
		(legacy_teardrops no)
	)
	(paper "A4")
	(title_block
		(title "03242023_DA0F0TMBIJ0_F0T_Motherboard_J_brd_V01_OCP.brd")
		(comment 1 "Grand Teton / footprints 2092-2098 of 6105")
	)
	(layers
		(0 "F.Cu" signal "TOP")
		(4 "In1.Cu" signal "GND")
		(6 "In2.Cu" signal "IN1")
		(8 "In3.Cu" signal "GND1")
		(10 "In4.Cu" signal "IN2")
		(12 "In5.Cu" signal "GND2")
		(14 "In6.Cu" signal "IN3")
		(16 "In7.Cu" signal "GND3")
		(18 "In8.Cu" signal "VCC")
		(20 "In9.Cu" signal "VCC1")
		(22 "In10.Cu" signal "GND4")
		(24 "In11.Cu" signal "IN4")
		(26 "In12.Cu" signal "GND5")
		(28 "In13.Cu" signal "IN5")
		(30 "In14.Cu" signal "GND6")
		(32 "In15.Cu" signal "IN6")
		(34 "In16.Cu" signal "GND7")
		(2 "B.Cu" signal "BOTTOM")
		(9 "F.Adhes" user "F.Adhesive")
		(11 "B.Adhes" user "B.Adhesive")
		(13 "F.Paste" user "Package Geometry/Pastemask Top")
		(15 "B.Paste" user "Package Geometry/Pastemask Bottom")
		(5 "F.SilkS" user "Ref Des/Silkscreen Top")
		(7 "B.SilkS" user "Ref Des/Silkscreen Bottom")
		(1 "F.Mask" user "Board Geometry/Soldermask Top")
		(3 "B.Mask" user "Board Geometry/Soldermask Bottom")
		(17 "Dwgs.User" user "User.Drawings")
		(19 "Cmts.User" user "User.Comments")
		(21 "Eco1.User" user "User.Eco1")
		(23 "Eco2.User" user "User.Eco2")
		(25 "Edge.Cuts" user "Board Geometry/Outline")
		(27 "Margin" user)
		(31 "F.CrtYd" user "Package Geometry/Place Bound Top")
		(29 "B.CrtYd" user "Package Geometry/Place Bound Bottom")
		(35 "F.Fab" user "Ref Des/Assembly Top")
		(33 "B.Fab" user "Ref Des/Assembly Bottom")
	)
	(footprint ""
		(layer "F.Cu")
		(at 207.772 -97.6884 90)
		(property "Reference" "R4784"
			(at 0 0 90)
			(layer "F.SilkS")
			(hide yes)
			(effects
				(font
					(size 1.27 1.27)
				)
			)
		)
		(property "Value" ""
			(at 0 0 90)
			(layer "F.Fab")
			(effects
				(font
					(size 1.27 1.27)
				)
			)
		)
		(duplicate_pad_numbers_are_jumpers no)
		(fp_line
			(start 0.7874 -0.4064)
			(end 0.7874 0.4064)
			(stroke
				(width 0.1524)
				(type default)
			)
			(layer "F.SilkS")
		)
		(fp_line
			(start -0.7874 -0.4064)
			(end 0.7874 -0.4064)
			(stroke
				(width 0.1524)
				(type default)
			)
			(layer "F.SilkS")
		)
		(fp_line
			(start 0.7874 0.4064)
			(end -0.7874 0.4064)
			(stroke
				(width 0.1524)
				(type default)
			)
			(layer "F.SilkS")
		)
		(fp_line
			(start -0.7874 0.4064)
			(end -0.7874 -0.4064)
			(stroke
				(width 0.1524)
				(type default)
			)
			(layer "F.SilkS")
		)
		(fp_line
			(start -0.12065 -0.305054)
			(end -0.12065 -0.2794)
			(stroke
				(width 0.1)
				(type default)
			)
			(layer "F.Fab")
		)
		(fp_line
			(start -0.67945 -0.305054)
			(end -0.12065 -0.305054)
			(stroke
				(width 0.1)
				(type default)
			)
			(layer "F.Fab")
		)
		(fp_line
			(start 0.67945 -0.3048)
			(end 0.67945 0.3048)
			(stroke
				(width 0.1)
				(type default)
			)
			(layer "F.Fab")
		)
		(fp_line
			(start 0.12065 -0.3048)
			(end 0.67945 -0.3048)
			(stroke
				(width 0.1)
				(type default)
			)
			(layer "F.Fab")
		)
		(fp_line
			(start 0.12065 -0.2794)
			(end 0.12065 -0.3048)
			(stroke
				(width 0.1)
				(type default)
			)
			(layer "F.Fab")
		)
		(fp_line
			(start -0.12065 -0.2794)
			(end 0.12065 -0.2794)
			(stroke
				(width 0.1)
				(type default)
			)
			(layer "F.Fab")
		)
		(fp_line
			(start 0.120396 0.2794)
			(end -0.12065 0.2794)
			(stroke
				(width 0.1)
				(type default)
			)
			(layer "F.Fab")
		)
		(fp_line
			(start -0.12065 0.2794)
			(end -0.12065 0.3048)
			(stroke
				(width 0.1)
				(type default)
			)
			(layer "F.Fab")
		)
		(fp_line
			(start 0.67945 0.3048)
			(end 0.120396 0.3048)
			(stroke
				(width 0.1)
				(type default)
			)
			(layer "F.Fab")
		)
		(fp_line
			(start 0.120396 0.3048)
			(end 0.120396 0.2794)
			(stroke
				(width 0.1)
				(type default)
			)
			(layer "F.Fab")
		)
		(fp_line
			(start -0.12065 0.3048)
			(end -0.67945 0.3048)
			(stroke
				(width 0.1)
				(type default)
			)
			(layer "F.Fab")
		)
		(fp_line
			(start -0.67945 0.3048)
			(end -0.67945 -0.305054)
			(stroke
				(width 0.1)
				(type default)
			)
			(layer "F.Fab")
		)
		(pad "1" smd circle
			(at -0.40005 0 90)
			(size 0 0)
			(layers "F.Cu" "F.Mask" "F.Paste")
			(net "P3V3_AUX")
		)
		(pad "2" smd circle
			(at 0.40005 0 90)
			(size 0 0)
			(layers "F.Cu" "F.Mask" "F.Paste")
			(net "FM_UV_ADR_TRIGGER_N")
		)
	)
	(footprint ""
		(layer "F.Cu")
		(at 192.052448 -401.112482)
		(property "Reference" "R3934"
			(at 0 0 0)
			(layer "F.SilkS")
			(hide yes)
			(effects
				(font
					(size 1.27 1.27)
				)
			)
		)
		(property "Value" ""
			(at 0 0 0)
			(layer "F.Fab")
			(effects
				(font
					(size 1.27 1.27)
				)
			)
		)
		(duplicate_pad_numbers_are_jumpers no)
		(fp_line
			(start -0.7874 -0.4064)
			(end 0.7874 -0.4064)
			(stroke
				(width 0.1524)
				(type default)
			)
			(layer "F.SilkS")
		)
		(fp_line
			(start -0.7874 0.4064)
			(end -0.7874 -0.4064)
			(stroke
				(width 0.1524)
				(type default)
			)
			(layer "F.SilkS")
		)
		(fp_line
			(start 0.7874 -0.4064)
			(end 0.7874 0.4064)
			(stroke
				(width 0.1524)
				(type default)
			)
			(layer "F.SilkS")
		)
		(fp_line
			(start 0.7874 0.4064)
			(end -0.7874 0.4064)
			(stroke
				(width 0.1524)
				(type default)
			)
			(layer "F.SilkS")
		)
		(fp_line
			(start -0.67945 -0.305054)
			(end -0.12065 -0.305054)
			(stroke
				(width 0.1)
				(type default)
			)
			(layer "F.Fab")
		)
		(fp_line
			(start -0.67945 0.3048)
			(end -0.67945 -0.305054)
			(stroke
				(width 0.1)
				(type default)
			)
			(layer "F.Fab")
		)
		(fp_line
			(start -0.12065 -0.305054)
			(end -0.12065 -0.2794)
			(stroke
				(width 0.1)
				(type default)
			)
			(layer "F.Fab")
		)
		(fp_line
			(start -0.12065 -0.2794)
			(end 0.12065 -0.2794)
			(stroke
				(width 0.1)
				(type default)
			)
			(layer "F.Fab")
		)
		(fp_line
			(start -0.12065 0.2794)
			(end -0.12065 0.3048)
			(stroke
				(width 0.1)
				(type default)
			)
			(layer "F.Fab")
		)
		(fp_line
			(start -0.12065 0.3048)
			(end -0.67945 0.3048)
			(stroke
				(width 0.1)
				(type default)
			)
			(layer "F.Fab")
		)
		(fp_line
			(start 0.120396 0.2794)
			(end -0.12065 0.2794)
			(stroke
				(width 0.1)
				(type default)
			)
			(layer "F.Fab")
		)
		(fp_line
			(start 0.120396 0.3048)
			(end 0.120396 0.2794)
			(stroke
				(width 0.1)
				(type default)
			)
			(layer "F.Fab")
		)
		(fp_line
			(start 0.12065 -0.3048)
			(end 0.67945 -0.3048)
			(stroke
				(width 0.1)
				(type default)
			)
			(layer "F.Fab")
		)
		(fp_line
			(start 0.12065 -0.2794)
			(end 0.12065 -0.3048)
			(stroke
				(width 0.1)
				(type default)
			)
			(layer "F.Fab")
		)
		(fp_line
			(start 0.67945 -0.3048)
			(end 0.67945 0.3048)
			(stroke
				(width 0.1)
				(type default)
			)
			(layer "F.Fab")
		)
		(fp_line
			(start 0.67945 0.3048)
			(end 0.120396 0.3048)
			(stroke
				(width 0.1)
				(type default)
			)
			(layer "F.Fab")
		)
		(pad "1" smd circle
			(at -0.40005 0)
			(size 0 0)
			(layers "F.Cu" "F.Mask" "F.Paste")
			(net "HSC_D_OC_R")
		)
		(pad "2" smd circle
			(at 0.40005 0)
			(size 0 0)
			(layers "F.Cu" "F.Mask" "F.Paste")
			(net "HSC_D_OC")
		)
	)
	(footprint ""
		(layer "F.Cu")
		(at 297.147234 -16.715994 180)
		(property "Reference" "R4204"
			(at 0 0 180)
			(layer "F.SilkS")
			(hide yes)
			(effects
				(font
					(size 1.27 1.27)
				)
			)
		)
		(property "Value" ""
			(at 0 0 180)
			(layer "F.Fab")
			(effects
				(font
					(size 1.27 1.27)
				)
			)
		)
		(duplicate_pad_numbers_are_jumpers no)
		(fp_line
			(start 0.7874 0.4064)
			(end -0.7874 0.4064)
			(stroke
				(width 0.1524)
				(type default)
			)
			(layer "F.SilkS")
		)
		(fp_line
			(start 0.7874 -0.4064)
			(end 0.7874 0.4064)
			(stroke
				(width 0.1524)
				(type default)
			)
			(layer "F.SilkS")
		)
		(fp_line
			(start -0.7874 0.4064)
			(end -0.7874 -0.4064)
			(stroke
				(width 0.1524)
				(type default)
			)
			(layer "F.SilkS")
		)
		(fp_line
			(start -0.7874 -0.4064)
			(end 0.7874 -0.4064)
			(stroke
				(width 0.1524)
				(type default)
			)
			(layer "F.SilkS")
		)
		(fp_line
			(start 0.67945 0.3048)
			(end 0.120396 0.3048)
			(stroke
				(width 0.1)
				(type default)
			)
			(layer "F.Fab")
		)
		(fp_line
			(start 0.67945 -0.3048)
			(end 0.67945 0.3048)
			(stroke
				(width 0.1)
				(type default)
			)
			(layer "F.Fab")
		)
		(fp_line
			(start 0.12065 -0.2794)
			(end 0.12065 -0.3048)
			(stroke
				(width 0.1)
				(type default)
			)
			(layer "F.Fab")
		)
		(fp_line
			(start 0.12065 -0.3048)
			(end 0.67945 -0.3048)
			(stroke
				(width 0.1)
				(type default)
			)
			(layer "F.Fab")
		)
		(fp_line
			(start 0.120396 0.3048)
			(end 0.120396 0.2794)
			(stroke
				(width 0.1)
				(type default)
			)
			(layer "F.Fab")
		)
		(fp_line
			(start 0.120396 0.2794)
			(end -0.12065 0.2794)
			(stroke
				(width 0.1)
				(type default)
			)
			(layer "F.Fab")
		)
		(fp_line
			(start -0.12065 0.3048)
			(end -0.67945 0.3048)
			(stroke
				(width 0.1)
				(type default)
			)
			(layer "F.Fab")
		)
		(fp_line
			(start -0.12065 0.2794)
			(end -0.12065 0.3048)
			(stroke
				(width 0.1)
				(type default)
			)
			(layer "F.Fab")
		)
		(fp_line
			(start -0.12065 -0.2794)
			(end 0.12065 -0.2794)
			(stroke
				(width 0.1)
				(type default)
			)
			(layer "F.Fab")
		)
		(fp_line
			(start -0.12065 -0.305054)
			(end -0.12065 -0.2794)
			(stroke
				(width 0.1)
				(type default)
			)
			(layer "F.Fab")
		)
		(fp_line
			(start -0.67945 0.3048)
			(end -0.67945 -0.305054)
			(stroke
				(width 0.1)
				(type default)
			)
			(layer "F.Fab")
		)
		(fp_line
			(start -0.67945 -0.305054)
			(end -0.12065 -0.305054)
			(stroke
				(width 0.1)
				(type default)
			)
			(layer "F.Fab")
		)
		(pad "1" smd circle
			(at -0.40005 0 180)
			(size 0 0)
			(layers "F.Cu" "F.Mask" "F.Paste")
			(net "P3V3_AUX")
		)
		(pad "2" smd circle
			(at 0.40005 0 180)
			(size 0 0)
			(layers "F.Cu" "F.Mask" "F.Paste")
			(net "U271_1_ADD0")
		)
	)
	(footprint ""
		(layer "F.Cu")
		(at 50.317654 -162.280854)
		(property "Reference" "PC1371"
			(at 0 0 0)
			(layer "F.SilkS")
			(hide yes)
			(effects
				(font
					(size 1.27 1.27)
				)
			)
		)
		(property "Value" ""
			(at 0 0 0)
			(layer "F.Fab")
			(effects
				(font
					(size 1.27 1.27)
				)
			)
		)
		(duplicate_pad_numbers_are_jumpers no)
		(fp_line
			(start -0.7874 -0.4064)
			(end 0.7874 -0.4064)
			(stroke
				(width 0.1524)
				(type default)
			)
			(layer "F.SilkS")
		)
		(fp_line
			(start -0.7874 0.4064)
			(end -0.7874 -0.4064)
			(stroke
				(width 0.1524)
				(type default)
			)
			(layer "F.SilkS")
		)
		(fp_line
			(start 0.7874 -0.4064)
			(end 0.7874 0.4064)
			(stroke
				(width 0.1524)
				(type default)
			)
			(layer "F.SilkS")
		)
		(fp_line
			(start 0.7874 0.4064)
			(end -0.7874 0.4064)
			(stroke
				(width 0.1524)
				(type default)
			)
			(layer "F.SilkS")
		)
		(fp_line
			(start -0.67945 -0.305054)
			(end -0.12065 -0.305054)
			(stroke
				(width 0.1)
				(type default)
			)
			(layer "F.Fab")
		)
		(fp_line
			(start -0.67945 0.3048)
			(end -0.67945 -0.305054)
			(stroke
				(width 0.1)
				(type default)
			)
			(layer "F.Fab")
		)
		(fp_line
			(start -0.12065 -0.305054)
			(end -0.12065 -0.2794)
			(stroke
				(width 0.1)
				(type default)
			)
			(layer "F.Fab")
		)
		(fp_line
			(start -0.12065 -0.2794)
			(end 0.12065 -0.2794)
			(stroke
				(width 0.1)
				(type default)
			)
			(layer "F.Fab")
		)
		(fp_line
			(start -0.12065 0.2794)
			(end -0.12065 0.3048)
			(stroke
				(width 0.1)
				(type default)
			)
			(layer "F.Fab")
		)
		(fp_line
			(start -0.12065 0.3048)
			(end -0.67945 0.3048)
			(stroke
				(width 0.1)
				(type default)
			)
			(layer "F.Fab")
		)
		(fp_line
			(start 0.120396 0.2794)
			(end -0.12065 0.2794)
			(stroke
				(width 0.1)
				(type default)
			)
			(layer "F.Fab")
		)
		(fp_line
			(start 0.120396 0.3048)
			(end 0.120396 0.2794)
			(stroke
				(width 0.1)
				(type default)
			)
			(layer "F.Fab")
		)
		(fp_line
			(start 0.12065 -0.3048)
			(end 0.67945 -0.3048)
			(stroke
				(width 0.1)
				(type default)
			)
			(layer "F.Fab")
		)
		(fp_line
			(start 0.12065 -0.2794)
			(end 0.12065 -0.3048)
			(stroke
				(width 0.1)
				(type default)
			)
			(layer "F.Fab")
		)
		(fp_line
			(start 0.67945 -0.3048)
			(end 0.67945 0.3048)
			(stroke
				(width 0.1)
				(type default)
			)
			(layer "F.Fab")
		)
		(fp_line
			(start 0.67945 0.3048)
			(end 0.120396 0.3048)
			(stroke
				(width 0.1)
				(type default)
			)
			(layer "F.Fab")
		)
		(pad "1" smd circle
			(at -0.40005 0)
			(size 0 0)
			(layers "F.Cu" "F.Mask" "F.Paste")
			(net "GND")
		)
		(pad "2" smd circle
			(at 0.40005 0)
			(size 0 0)
			(layers "F.Cu" "F.Mask" "F.Paste")
			(net "PVCCD_HV_CPU1_VREF")
		)
	)
	(footprint ""
		(layer "F.Cu")
		(at 15.494 -426.1358 -90)
		(property "Reference" "R4802"
			(at 0 0 270)
			(layer "F.SilkS")
			(hide yes)
			(effects
				(font
					(size 1.27 1.27)
				)
			)
		)
		(property "Value" ""
			(at 0 0 270)
			(layer "F.Fab")
			(effects
				(font
					(size 1.27 1.27)
				)
			)
		)
		(duplicate_pad_numbers_are_jumpers no)
		(fp_line
			(start -0.7874 0.4064)
			(end -0.7874 -0.4064)
			(stroke
				(width 0.1524)
				(type default)
			)
			(layer "F.SilkS")
		)
		(fp_line
			(start 0.7874 0.4064)
			(end -0.7874 0.4064)
			(stroke
				(width 0.1524)
				(type default)
			)
			(layer "F.SilkS")
		)
		(fp_line
			(start -0.7874 -0.4064)
			(end 0.7874 -0.4064)
			(stroke
				(width 0.1524)
				(type default)
			)
			(layer "F.SilkS")
		)
		(fp_line
			(start 0.7874 -0.4064)
			(end 0.7874 0.4064)
			(stroke
				(width 0.1524)
				(type default)
			)
			(layer "F.SilkS")
		)
		(fp_line
			(start -0.67945 0.3048)
			(end -0.67945 -0.305054)
			(stroke
				(width 0.1)
				(type default)
			)
			(layer "F.Fab")
		)
		(fp_line
			(start -0.12065 0.3048)
			(end -0.67945 0.3048)
			(stroke
				(width 0.1)
				(type default)
			)
			(layer "F.Fab")
		)
		(fp_line
			(start 0.120396 0.3048)
			(end 0.120396 0.2794)
			(stroke
				(width 0.1)
				(type default)
			)
			(layer "F.Fab")
		)
		(fp_line
			(start 0.67945 0.3048)
			(end 0.120396 0.3048)
			(stroke
				(width 0.1)
				(type default)
			)
			(layer "F.Fab")
		)
		(fp_line
			(start -0.12065 0.2794)
			(end -0.12065 0.3048)
			(stroke
				(width 0.1)
				(type default)
			)
			(layer "F.Fab")
		)
		(fp_line
			(start 0.120396 0.2794)
			(end -0.12065 0.2794)
			(stroke
				(width 0.1)
				(type default)
			)
			(layer "F.Fab")
		)
		(fp_line
			(start -0.12065 -0.2794)
			(end 0.12065 -0.2794)
			(stroke
				(width 0.1)
				(type default)
			)
			(layer "F.Fab")
		)
		(fp_line
			(start 0.12065 -0.2794)
			(end 0.12065 -0.3048)
			(stroke
				(width 0.1)
				(type default)
			)
			(layer "F.Fab")
		)
		(fp_line
			(start 0.12065 -0.3048)
			(end 0.67945 -0.3048)
			(stroke
				(width 0.1)
				(type default)
			)
			(layer "F.Fab")
		)
		(fp_line
			(start 0.67945 -0.3048)
			(end 0.67945 0.3048)
			(stroke
				(width 0.1)
				(type default)
			)
			(layer "F.Fab")
		)
		(fp_line
			(start -0.67945 -0.305054)
			(end -0.12065 -0.305054)
			(stroke
				(width 0.1)
				(type default)
			)
			(layer "F.Fab")
		)
		(fp_line
			(start -0.12065 -0.305054)
			(end -0.12065 -0.2794)
			(stroke
				(width 0.1)
				(type default)
			)
			(layer "F.Fab")
		)
		(pad "1" smd circle
			(at -0.40005 0 270)
			(size 0 0)
			(layers "F.Cu" "F.Mask" "F.Paste")
			(net "PRSNT_CABLE_GPU_A3_ISO_N")
		)
		(pad "2" smd circle
			(at 0.40005 0 270)
			(size 0 0)
			(layers "F.Cu" "F.Mask" "F.Paste")
			(net "PRSNT_CABLE_GPU_A3_ISO_R_N")
		)
	)
	(footprint ""
		(layer "F.Cu")
		(at 403.985984 -17.612614 90)
		(property "Reference" "C848"
			(at 0 0 90)
			(layer "F.SilkS")
			(hide yes)
			(effects
				(font
					(size 1.27 1.27)
				)
			)
		)
		(property "Value" ""
			(at 0 0 90)
			(layer "F.Fab")
			(effects
				(font
					(size 1.27 1.27)
				)
			)
		)
		(duplicate_pad_numbers_are_jumpers no)
		(fp_line
			(start 0.299974 -0.150114)
			(end 0.299974 0.150114)
			(stroke
				(width 0.1)
				(type default)
			)
			(layer "F.Fab")
		)
		(fp_line
			(start -0.299974 -0.150114)
			(end 0.299974 -0.150114)
			(stroke
				(width 0.1)
				(type default)
			)
			(layer "F.Fab")
		)
		(fp_line
			(start 0.299974 0.150114)
			(end -0.299974 0.150114)
			(stroke
				(width 0.1)
				(type default)
			)
			(layer "F.Fab")
		)
		(fp_line
			(start -0.299974 0.150114)
			(end -0.299974 -0.150114)
			(stroke
				(width 0.1)
				(type default)
			)
			(layer "F.Fab")
		)
		(pad "1" smd rect
			(at -0.2667 0 90)
			(size 0.3048 0.381)
			(layers "F.Cu" "F.Mask" "F.Paste")
			(net "P5E_CPU0_PE1_TX_C_DN<10>")
		)
		(pad "2" smd rect
			(at 0.2667 0 90)
			(size 0.3048 0.381)
			(layers "F.Cu" "F.Mask" "F.Paste")
			(net "P5E_CPU0_PE1_TX_DN<10>")
		)
	)
	(footprint ""
		(layer "F.Cu")
		(at 117.526816 -240.277142 90)
		(property "Reference" "C223"
			(at 0 0 90)
			(layer "F.SilkS")
			(hide yes)
			(effects
				(font
					(size 1.27 1.27)
				)
			)
		)
		(property "Value" ""
			(at 0 0 90)
			(layer "F.Fab")
			(effects
				(font
					(size 1.27 1.27)
				)
			)
		)
		(duplicate_pad_numbers_are_jumpers no)
		(fp_line
			(start 0.7874 -0.4064)
			(end 0.7874 0.4064)
			(stroke
				(width 0.1524)
				(type default)
			)
			(layer "F.SilkS")
		)
		(fp_line
			(start -0.7874 -0.4064)
			(end 0.7874 -0.4064)
			(stroke
				(width 0.1524)
				(type default)
			)
			(layer "F.SilkS")
		)
		(fp_line
			(start 0.7874 0.4064)
			(end -0.7874 0.4064)
			(stroke
				(width 0.1524)
				(type default)
			)
			(layer "F.SilkS")
		)
		(fp_line
			(start -0.7874 0.4064)
			(end -0.7874 -0.4064)
			(stroke
				(width 0.1524)
				(type default)
			)
			(layer "F.SilkS")
		)
		(fp_line
			(start -0.12065 -0.305054)
			(end -0.12065 -0.2794)
			(stroke
				(width 0.1)
				(type default)
			)
			(layer "F.Fab")
		)
		(fp_line
			(start -0.67945 -0.305054)
			(end -0.12065 -0.305054)
			(stroke
				(width 0.1)
				(type default)
			)
			(layer "F.Fab")
		)
		(fp_line
			(start 0.67945 -0.3048)
			(end 0.67945 0.3048)
			(stroke
				(width 0.1)
				(type default)
			)
			(layer "F.Fab")
		)
		(fp_line
			(start 0.12065 -0.3048)
			(end 0.67945 -0.3048)
			(stroke
				(width 0.1)
				(type default)
			)
			(layer "F.Fab")
		)
		(fp_line
			(start 0.12065 -0.2794)
			(end 0.12065 -0.3048)
			(stroke
				(width 0.1)
				(type default)
			)
			(layer "F.Fab")
		)
		(fp_line
			(start -0.12065 -0.2794)
			(end 0.12065 -0.2794)
			(stroke
				(width 0.1)
				(type default)
			)
			(layer "F.Fab")
		)
		(fp_line
			(start 0.120396 0.2794)
			(end -0.12065 0.2794)
			(stroke
				(width 0.1)
				(type default)
			)
			(layer "F.Fab")
		)
		(fp_line
			(start -0.12065 0.2794)
			(end -0.12065 0.3048)
			(stroke
				(width 0.1)
				(type default)
			)
			(layer "F.Fab")
		)
		(fp_line
			(start 0.67945 0.3048)
			(end 0.120396 0.3048)
			(stroke
				(width 0.1)
				(type default)
			)
			(layer "F.Fab")
		)
		(fp_line
			(start 0.120396 0.3048)
			(end 0.120396 0.2794)
			(stroke
				(width 0.1)
				(type default)
			)
			(layer "F.Fab")
		)
		(fp_line
			(start -0.12065 0.3048)
			(end -0.67945 0.3048)
			(stroke
				(width 0.1)
				(type default)
			)
			(layer "F.Fab")
		)
		(fp_line
			(start -0.67945 0.3048)
			(end -0.67945 -0.305054)
			(stroke
				(width 0.1)
				(type default)
			)
			(layer "F.Fab")
		)
		(pad "1" smd circle
			(at -0.40005 0 90)
			(size 0 0)
			(layers "F.Cu" "F.Mask" "F.Paste")
			(net "PVCCIN_CPU1")
		)
		(pad "2" smd circle
			(at 0.40005 0 90)
			(size 0 0)
			(layers "F.Cu" "F.Mask" "F.Paste")
			(net "GND")
		)
	)
)
